# T6G (Grand Teton) — schematic netlist excerpt (pin names and nets, part order shuffled) for the footprints in the layout excerpt that follows; sources: Cadence DE-HDL packaged netlist, KiCad conversion of 04192023_DAF0TMB3IC0_F0TG_MB_C_brd_V02_OCP.brd

C6559  Q_CAP_DIFFBUS  DIFF BUS_0.22UF 6.3V 20% X6S  pkg C0201  page 286 : \1\ = P5E_CPU0_P1_TX_BUF_C_DP<13> ; \2\ = P5E_CPU0_P1_TX_BUF_DP<13>
PR376  Q_RES  40.2K 1% CHIP  pkg 0402LF  page 224 : A = P5V_AUX ; B = PVDD11_S3_P1_VMON
C2352  Q_CAP  22UF 4V 20% X6S  pkg C0402  page 73 : A = PVDDCR_CPU1_P1 ; B = GND

(kicad_pcb
	(version 20260206)
	(generator "pcbnew")
	(generator_version "10.0")
	(general
		(thickness 1.6)
		(legacy_teardrops no)
	)
	(paper "A4")
	(title_block
		(title "04192023_DAF0TMB3IC0_F0TG_MB_C_brd_V02_OCP.brd")
		(comment 1 "Grand Teton / footprints 7051-7053 of 8354")
	)
	(layers
		(0 "F.Cu" signal "TOP")
		(4 "In1.Cu" signal "GND")
		(6 "In2.Cu" signal "IN1")
		(8 "In3.Cu" signal "GND1")
		(10 "In4.Cu" signal "IN2")
		(12 "In5.Cu" signal "GND2")
		(14 "In6.Cu" signal "IN3")
		(16 "In7.Cu" signal "GND3")
		(18 "In8.Cu" signal "VCC")
		(20 "In9.Cu" signal "VCC1")
		(22 "In10.Cu" signal "GND4")
		(24 "In11.Cu" signal "IN4")
		(26 "In12.Cu" signal "GND5")
		(28 "In13.Cu" signal "IN5")
		(30 "In14.Cu" signal "GND6")
		(32 "In15.Cu" signal "IN6")
		(34 "In16.Cu" signal "GND7")
		(2 "B.Cu" signal "BOTTOM")
		(9 "F.Adhes" user "F.Adhesive")
		(11 "B.Adhes" user "B.Adhesive")
		(13 "F.Paste" user "Package Geometry/Pastemask Top")
		(15 "B.Paste" user "Package Geometry/Pastemask Bottom")
		(5 "F.SilkS" user "Ref Des/Silkscreen Top")
		(7 "B.SilkS" user "Ref Des/Silkscreen Bottom")
		(1 "F.Mask" user "Board Geometry/Soldermask Top")
		(3 "B.Mask" user "Board Geometry/Soldermask Bottom")
		(17 "Dwgs.User" user "User.Drawings")
		(19 "Cmts.User" user "User.Comments")
		(21 "Eco1.User" user "User.Eco1")
		(23 "Eco2.User" user "User.Eco2")
		(25 "Edge.Cuts" user "Board Geometry/Outline")
		(27 "Margin" user)
		(31 "F.CrtYd" user "Package Geometry/Place Bound Top")
		(29 "B.CrtYd" user "Package Geometry/Place Bound Bottom")
		(35 "F.Fab" user "Ref Des/Assembly Top")
		(33 "B.Fab" user "Ref Des/Assembly Bottom")
	)
	(footprint ""
		(layer "B.Cu")
		(at 346.036646 -416.899344 90)
		(property "Reference" "C6559"
			(at 0 0 90)
			(layer "B.SilkS")
			(hide yes)
			(effects
				(font
					(size 1.27 1.27)
				)
				(justify mirror)
			)
		)
		(property "Value" ""
			(at 0 0 90)
			(layer "B.Fab")
			(effects
				(font
					(size 1.27 1.27)
				)
				(justify mirror)
			)
		)
		(duplicate_pad_numbers_are_jumpers no)
		(fp_line
			(start 0.299974 -0.150114)
			(end -0.299974 -0.150114)
			(stroke
				(width 0.1)
				(type default)
			)
			(layer "B.Fab")
		)
		(fp_line
			(start -0.299974 -0.150114)
			(end -0.299974 0.150114)
			(stroke
				(width 0.1)
				(type default)
			)
			(layer "B.Fab")
		)
		(fp_line
			(start 0.299974 0.150114)
			(end 0.299974 -0.150114)
			(stroke
				(width 0.1)
				(type default)
			)
			(layer "B.Fab")
		)
		(fp_line
			(start -0.299974 0.150114)
			(end 0.299974 0.150114)
			(stroke
				(width 0.1)
				(type default)
			)
			(layer "B.Fab")
		)
		(pad "1" smd rect
			(at 0.2667 0 270)
			(size 0.3048 0.381)
			(layers "B.Cu" "B.Mask" "B.Paste")
			(net "P5E_CPU0_P1_TX_BUF_C_DP<13>")
		)
		(pad "2" smd rect
			(at -0.2667 0 270)
			(size 0.3048 0.381)
			(layers "B.Cu" "B.Mask" "B.Paste")
			(net "P5E_CPU0_P1_TX_BUF_DP<13>")
		)
	)
	(footprint ""
		(layer "B.Cu")
		(at 115.93322 -267.529564)
		(property "Reference" "C2352"
			(at 0 0 0)
			(layer "B.SilkS")
			(hide yes)
			(effects
				(font
					(size 1.27 1.27)
				)
				(justify mirror)
			)
		)
		(property "Value" ""
			(at 0 0 0)
			(layer "B.Fab")
			(effects
				(font
					(size 1.27 1.27)
				)
				(justify mirror)
			)
		)
		(duplicate_pad_numbers_are_jumpers no)
		(fp_line
			(start -0.7874 -0.4064)
			(end -0.7874 0.4064)
			(stroke
				(width 0.1524)
				(type default)
			)
			(layer "B.SilkS")
		)
		(fp_line
			(start -0.7874 0.4064)
			(end 0.7874 0.4064)
			(stroke
				(width 0.1524)
				(type default)
			)
			(layer "B.SilkS")
		)
		(fp_line
			(start 0.7874 -0.4064)
			(end -0.7874 -0.4064)
			(stroke
				(width 0.1524)
				(type default)
			)
			(layer "B.SilkS")
		)
		(fp_line
			(start 0.7874 0.4064)
			(end 0.7874 -0.4064)
			(stroke
				(width 0.1524)
				(type default)
			)
			(layer "B.SilkS")
		)
		(fp_line
			(start -0.67945 -0.3048)
			(end -0.67945 0.3048)
			(stroke
				(width 0.1)
				(type default)
			)
			(layer "B.Fab")
		)
		(fp_line
			(start -0.67945 0.3048)
			(end -0.120396 0.3048)
			(stroke
				(width 0.1)
				(type default)
			)
			(layer "B.Fab")
		)
		(fp_line
			(start -0.12065 -0.3048)
			(end -0.67945 -0.3048)
			(stroke
				(width 0.1)
				(type default)
			)
			(layer "B.Fab")
		)
		(fp_line
			(start -0.12065 -0.2794)
			(end -0.12065 -0.3048)
			(stroke
				(width 0.1)
				(type default)
			)
			(layer "B.Fab")
		)
		(fp_line
			(start -0.120396 0.2794)
			(end 0.12065 0.2794)
			(stroke
				(width 0.1)
				(type default)
			)
			(layer "B.Fab")
		)
		(fp_line
			(start -0.120396 0.3048)
			(end -0.120396 0.2794)
			(stroke
				(width 0.1)
				(type default)
			)
			(layer "B.Fab")
		)
		(fp_line
			(start 0.12065 -0.305054)
			(end 0.12065 -0.2794)
			(stroke
				(width 0.1)
				(type default)
			)
			(layer "B.Fab")
		)
		(fp_line
			(start 0.12065 -0.2794)
			(end -0.12065 -0.2794)
			(stroke
				(width 0.1)
				(type default)
			)
			(layer "B.Fab")
		)
		(fp_line
			(start 0.12065 0.2794)
			(end 0.12065 0.3048)
			(stroke
				(width 0.1)
				(type default)
			)
			(layer "B.Fab")
		)
		(fp_line
			(start 0.12065 0.3048)
			(end 0.67945 0.3048)
			(stroke
				(width 0.1)
				(type default)
			)
			(layer "B.Fab")
		)
		(fp_line
			(start 0.67945 -0.305054)
			(end 0.12065 -0.305054)
			(stroke
				(width 0.1)
				(type default)
			)
			(layer "B.Fab")
		)
		(fp_line
			(start 0.67945 0.3048)
			(end 0.67945 -0.305054)
			(stroke
				(width 0.1)
				(type default)
			)
			(layer "B.Fab")
		)
		(pad "1" smd circle
			(at 0.40005 0 180)
			(size 0 0)
			(layers "B.Cu" "B.Mask" "B.Paste")
			(net "PVDDCR_CPU1_P1")
		)
		(pad "2" smd circle
			(at -0.40005 0 180)
			(size 0 0)
			(layers "B.Cu" "B.Mask" "B.Paste")
			(net "GND")
		)
	)
	(footprint ""
		(layer "B.Cu")
		(at 167.936418 -349.716344)
		(property "Reference" "PR376"
			(at 0 0 0)
			(layer "B.SilkS")
			(hide yes)
			(effects
				(font
					(size 1.27 1.27)
				)
				(justify mirror)
			)
		)
		(property "Value" ""
			(at 0 0 0)
			(layer "B.Fab")
			(effects
				(font
					(size 1.27 1.27)
				)
				(justify mirror)
			)
		)
		(duplicate_pad_numbers_are_jumpers no)
		(fp_line
			(start -0.7874 -0.4064)
			(end -0.7874 0.4064)
			(stroke
				(width 0.1524)
				(type default)
			)
			(layer "B.SilkS")
		)
		(fp_line
			(start -0.7874 0.4064)
			(end 0.7874 0.4064)
			(stroke
				(width 0.1524)
				(type default)
			)
			(layer "B.SilkS")
		)
		(fp_line
			(start 0.7874 -0.4064)
			(end -0.7874 -0.4064)
			(stroke
				(width 0.1524)
				(type default)
			)
			(layer "B.SilkS")
		)
		(fp_line
			(start 0.7874 0.4064)
			(end 0.7874 -0.4064)
			(stroke
				(width 0.1524)
				(type default)
			)
			(layer "B.SilkS")
		)
		(fp_line
			(start -0.67945 -0.3048)
			(end -0.67945 0.3048)
			(stroke
				(width 0.1)
				(type default)
			)
			(layer "B.Fab")
		)
		(fp_line
			(start -0.67945 0.3048)
			(end -0.120396 0.3048)
			(stroke
				(width 0.1)
				(type default)
			)
			(layer "B.Fab")
		)
		(fp_line
			(start -0.12065 -0.3048)
			(end -0.67945 -0.3048)
			(stroke
				(width 0.1)
				(type default)
			)
			(layer "B.Fab")
		)
		(fp_line
			(start -0.12065 -0.2794)
			(end -0.12065 -0.3048)
			(stroke
				(width 0.1)
				(type default)
			)
			(layer "B.Fab")
		)
		(fp_line
			(start -0.120396 0.2794)
			(end 0.12065 0.2794)
			(stroke
				(width 0.1)
				(type default)
			)
			(layer "B.Fab")
		)
		(fp_line
			(start -0.120396 0.3048)
			(end -0.120396 0.2794)
			(stroke
				(width 0.1)
				(type default)
			)
			(layer "B.Fab")
		)
		(fp_line
			(start 0.12065 -0.305054)
			(end 0.12065 -0.2794)
			(stroke
				(width 0.1)
				(type default)
			)
			(layer "B.Fab")
		)
		(fp_line
			(start 0.12065 -0.2794)
			(end -0.12065 -0.2794)
			(stroke
				(width 0.1)
				(type default)
			)
			(layer "B.Fab")
		)
		(fp_line
			(start 0.12065 0.2794)
			(end 0.12065 0.3048)
			(stroke
				(width 0.1)
				(type default)
			)
			(layer "B.Fab")
		)
		(fp_line
			(start 0.12065 0.3048)
			(end 0.67945 0.3048)
			(stroke
				(width 0.1)
				(type default)
			)
			(layer "B.Fab")
		)
		(fp_line
			(start 0.67945 -0.305054)
			(end 0.12065 -0.305054)
			(stroke
				(width 0.1)
				(type default)
			)
			(layer "B.Fab")
		)
		(fp_line
			(start 0.67945 0.3048)
			(end 0.67945 -0.305054)
			(stroke
				(width 0.1)
				(type default)
			)
			(layer "B.Fab")
		)
		(pad "1" smd circle
			(at 0.40005 0 180)
			(size 0 0)
			(layers "B.Cu" "B.Mask" "B.Paste")
			(net "P5V_AUX")
		)
		(pad "2" smd circle
			(at -0.40005 0 180)
			(size 0 0)
			(layers "B.Cu" "B.Mask" "B.Paste")
			(net "PVDD11_S3_P1_VMON")
		)
	)
)
